# BASEBOARD_FAB2 (Tioga Pass) — schematic netlist excerpt (pin names and nets, part order shuffled) for the footprints in the layout excerpt that follows; sources: Cadence DE-HDL packaged netlist, KiCad conversion of Wiwynn_Tioga_Pass_MB.brd

R2T11  RES  4.75K 1% CHIP  pkg 0402  page 154 : A = P3V3_STBY ; B = FM_DUAL_BIOS_SEL_N
C3N35  CAPP  470UF 2.5V 20% ALUM  pkg 3018  page 212 : A = PVCCIO_CPU0 ; B = GND
C5P11  CAP  100UF 4V 20% X5R  pkg 0805  page 42 : A = PVCCMCP_CPU0 ; B = GND

(kicad_pcb
	(version 20260206)
	(generator "pcbnew")
	(generator_version "10.0")
	(general
		(thickness 1.6)
		(legacy_teardrops no)
	)
	(paper "A4")
	(title_block
		(title "Wiwynn_Tioga_Pass_MB.brd")
		(comment 1 "Tioga Pass / footprints 2955-2957 of 4770")
	)
	(layers
		(0 "F.Cu" signal "TOP")
		(4 "In1.Cu" signal "L2GND")
		(6 "In2.Cu" signal "L3")
		(8 "In3.Cu" signal "L4GND")
		(10 "In4.Cu" signal "L5")
		(12 "In5.Cu" signal "L6GND")
		(14 "In6.Cu" signal "L7VCC")
		(16 "In7.Cu" signal "L8VCC")
		(18 "In8.Cu" signal "L9GND")
		(20 "In9.Cu" signal "L10")
		(22 "In10.Cu" signal "L11GND")
		(24 "In11.Cu" signal "L12")
		(26 "In12.Cu" signal "L13GND")
		(2 "B.Cu" signal "BOTTOM")
		(9 "F.Adhes" user "F.Adhesive")
		(11 "B.Adhes" user "B.Adhesive")
		(13 "F.Paste" user "Package Geometry/Pastemask Top")
		(15 "B.Paste" user "Package Geometry/Pastemask Bottom")
		(5 "F.SilkS" user "Ref Des/Silkscreen Top")
		(7 "B.SilkS" user "Ref Des/Silkscreen Bottom")
		(1 "F.Mask" user "Board Geometry/Soldermask Top")
		(3 "B.Mask" user "Board Geometry/Soldermask Bottom")
		(17 "Dwgs.User" user "User.Drawings")
		(19 "Cmts.User" user "User.Comments")
		(21 "Eco1.User" user "User.Eco1")
		(23 "Eco2.User" user "User.Eco2")
		(25 "Edge.Cuts" user "Board Geometry/Outline")
		(27 "Margin" user)
		(31 "F.CrtYd" user "Package Geometry/Place Bound Top")
		(29 "B.CrtYd" user "Package Geometry/Place Bound Bottom")
		(35 "F.Fab" user "Ref Des/Assembly Top")
		(33 "B.Fab" user "Ref Des/Assembly Bottom")
	)
	(footprint ""
		(layer "B.Cu")
		(at 389.1915 -61.341 -90)
		(property "Reference" "R2T11"
			(at 0 0 90)
			(layer "B.SilkS")
			(hide yes)
			(effects
				(font
					(size 1.27 1.27)
				)
				(justify mirror)
			)
		)
		(property "Value" ""
			(at 0 0 90)
			(layer "B.Fab")
			(effects
				(font
					(size 1.27 1.27)
				)
				(justify mirror)
			)
		)
		(duplicate_pad_numbers_are_jumpers no)
		(fp_poly
			(pts
				(xy 0.2794 -0.1016) (xy -0.2794 -0.1016) (xy -0.2794 0.9906) (xy 0.2794 0.9906)
			)
			(stroke
				(width 0)
				(type default)
			)
			(fill no)
			(layer "B.CrtYd")
		)
		(fp_line
			(start -0.2794 0.9906)
			(end -0.2794 -0.1016)
			(stroke
				(width 0.1)
				(type default)
			)
			(layer "B.Fab")
		)
		(fp_line
			(start 0.2794 0.9906)
			(end -0.2794 0.9906)
			(stroke
				(width 0.1)
				(type default)
			)
			(layer "B.Fab")
		)
		(fp_line
			(start -0.2794 -0.1016)
			(end 0.2794 -0.1016)
			(stroke
				(width 0.1)
				(type default)
			)
			(layer "B.Fab")
		)
		(fp_line
			(start 0.2794 -0.1016)
			(end 0.2794 0.9906)
			(stroke
				(width 0.1)
				(type default)
			)
			(layer "B.Fab")
		)
		(pad "1" smd rect
			(at 0 0 90)
			(size 0.508 0.508)
			(layers "B.Cu" "B.Mask" "B.Paste")
			(net "P3V3_STBY")
		)
		(pad "2" smd rect
			(at 0 0.889 90)
			(size 0.508 0.508)
			(layers "B.Cu" "B.Mask" "B.Paste")
			(net "FM_DUAL_BIOS_SEL_N")
		)
		(zone
			(layer "B.Cu")
			(hatch none 0.5)
			(connect_pads
				(clearance 0)
			)
			(min_thickness 0.25)
			(keepout
				(tracks not_allowed)
				(vias allowed)
				(pads allowed)
				(copperpour not_allowed)
				(footprints allowed)
			)
			(placement
				(enabled no)
				(sheetname "")
			)
			(fill
				(thermal_gap 0.5)
				(thermal_bridge_width 0.5)
				(island_removal_mode 0)
			)
			(polygon
				(pts
					(xy 388.5565 -61.087) (xy 388.5565 -61.595) (xy 388.9375 -61.595) (xy 388.9375 -61.087)
				)
			)
		)
		(zone
			(layer "B.Cu")
			(hatch none 0.5)
			(connect_pads
				(clearance 0)
			)
			(min_thickness 0.25)
			(keepout
				(tracks allowed)
				(vias not_allowed)
				(pads allowed)
				(copperpour not_allowed)
				(footprints allowed)
			)
			(placement
				(enabled no)
				(sheetname "")
			)
			(fill
				(thermal_gap 0.5)
				(thermal_bridge_width 0.5)
				(island_removal_mode 0)
			)
			(polygon
				(pts
					(xy 388.9375 -61.087) (xy 388.9375 -61.595) (xy 388.5565 -61.595) (xy 388.5565 -61.087)
				)
			)
		)
	)
	(footprint ""
		(layer "B.Cu")
		(at 336.042 -99.314 90)
		(property "Reference" "C3N35"
			(at 1.62433 -3.81 0)
			(unlocked yes)
			(layer "B.SilkS")
			(effects
				(font
					(size 0.7874 0.5842)
					(thickness 0.1524)
				)
				(justify mirror)
			)
		)
		(property "Value" ""
			(at 0 0 90)
			(layer "B.Fab")
			(effects
				(font
					(size 1.27 1.27)
				)
				(justify mirror)
			)
		)
		(duplicate_pad_numbers_are_jumpers no)
		(fp_line
			(start 2.563114 -1.616456)
			(end 2.563114 1.633728)
			(stroke
				(width 0.1524)
				(type default)
			)
			(layer "B.SilkS")
		)
		(fp_line
			(start 1.6002 -1.616456)
			(end 2.563114 -1.616456)
			(stroke
				(width 0.1524)
				(type default)
			)
			(layer "B.SilkS")
		)
		(fp_line
			(start -1.6002 -1.616456)
			(end -2.504948 -1.616456)
			(stroke
				(width 0.1524)
				(type default)
			)
			(layer "B.SilkS")
		)
		(fp_line
			(start -2.504948 -1.616456)
			(end -2.504948 1.633728)
			(stroke
				(width 0.1524)
				(type default)
			)
			(layer "B.SilkS")
		)
		(fp_line
			(start 2.563114 1.633728)
			(end 1.6002 1.633728)
			(stroke
				(width 0.1524)
				(type default)
			)
			(layer "B.SilkS")
		)
		(fp_line
			(start -2.504948 1.633728)
			(end -1.6002 1.633728)
			(stroke
				(width 0.1524)
				(type default)
			)
			(layer "B.SilkS")
		)
		(fp_line
			(start 2.286 7.366)
			(end 2.286 1.632712)
			(stroke
				(width 0.1524)
				(type default)
			)
			(layer "B.SilkS")
		)
		(fp_line
			(start 2.286 7.366)
			(end 1.60147 7.366)
			(stroke
				(width 0.1524)
				(type default)
			)
			(layer "B.SilkS")
		)
		(fp_line
			(start -2.286 7.366)
			(end -2.286 1.63195)
			(stroke
				(width 0.1524)
				(type default)
			)
			(layer "B.SilkS")
		)
		(fp_line
			(start -2.286 7.366)
			(end -1.600708 7.366)
			(stroke
				(width 0.1524)
				(type default)
			)
			(layer "B.SilkS")
		)
		(fp_rect
			(start 2.286 7.366)
			(end -2.286 -0.254)
			(stroke
				(width 0)
				(type default)
			)
			(fill no)
			(layer "B.CrtYd")
		)
		(fp_line
			(start 2.286 -0.254)
			(end -2.286 -0.254)
			(stroke
				(width 0.1)
				(type default)
			)
			(layer "B.Fab")
		)
		(fp_line
			(start -2.286 -0.254)
			(end -2.286 7.366)
			(stroke
				(width 0.1)
				(type default)
			)
			(layer "B.Fab")
		)
		(fp_line
			(start 2.286 7.366)
			(end 2.286 -0.254)
			(stroke
				(width 0.1)
				(type default)
			)
			(layer "B.Fab")
		)
		(fp_line
			(start -2.286 7.366)
			(end 2.286 7.366)
			(stroke
				(width 0.1)
				(type default)
			)
			(layer "B.Fab")
		)
		(pad "1" smd rect
			(at 0 0 270)
			(size 2.54 3.048)
			(layers "B.Cu" "B.Mask" "B.Paste")
			(net "PVCCIO_CPU0")
		)
		(pad "2" smd rect
			(at 0 7.112 270)
			(size 2.54 3.048)
			(layers "B.Cu" "B.Mask" "B.Paste")
			(net "GND")
		)
	)
	(footprint ""
		(layer "B.Cu")
		(at 273.560286 -79.60614 180)
		(property "Reference" "C5P11"
			(at 0 0 0)
			(layer "B.SilkS")
			(hide yes)
			(effects
				(font
					(size 1.27 1.27)
				)
				(justify mirror)
			)
		)
		(property "Value" ""
			(at 0 0 0)
			(layer "B.Fab")
			(effects
				(font
					(size 1.27 1.27)
				)
				(justify mirror)
			)
		)
		(duplicate_pad_numbers_are_jumpers no)
		(fp_poly
			(pts
				(xy 0.7239 -0.2159) (xy -0.7239 -0.2159) (xy -0.7239 1.9939) (xy 0.7239 1.9939)
			)
			(stroke
				(width 0)
				(type default)
			)
			(fill no)
			(layer "B.CrtYd")
		)
		(fp_line
			(start 0.7239 1.9939)
			(end -0.7239 1.9939)
			(stroke
				(width 0.1)
				(type default)
			)
			(layer "B.Fab")
		)
		(fp_line
			(start 0.7239 -0.2159)
			(end 0.7239 1.9939)
			(stroke
				(width 0.1)
				(type default)
			)
			(layer "B.Fab")
		)
		(fp_line
			(start -0.7239 1.9939)
			(end -0.7239 -0.2159)
			(stroke
				(width 0.1)
				(type default)
			)
			(layer "B.Fab")
		)
		(fp_line
			(start -0.7239 -0.2159)
			(end 0.7239 -0.2159)
			(stroke
				(width 0.1)
				(type default)
			)
			(layer "B.Fab")
		)
		(pad "1" smd rect
			(at 0 0)
			(size 1.27 1.016)
			(layers "B.Cu" "B.Mask" "B.Paste")
			(net "PVCCMCP_CPU0")
		)
		(pad "2" smd rect
			(at 0 1.778)
			(size 1.27 1.016)
			(layers "B.Cu" "B.Mask" "B.Paste")
			(net "GND")
		)
		(zone
			(layer "B.Cu")
			(hatch none 0.5)
			(connect_pads
				(clearance 0)
			)
			(min_thickness 0.25)
			(keepout
				(tracks not_allowed)
				(vias allowed)
				(pads allowed)
				(copperpour not_allowed)
				(footprints allowed)
			)
			(placement
				(enabled no)
				(sheetname "")
			)
			(fill
				(thermal_gap 0.5)
				(thermal_bridge_width 0.5)
				(island_removal_mode 0)
			)
			(polygon
				(pts
					(xy 272.925286 -80.11414) (xy 274.195286 -80.11414) (xy 274.195286 -80.87614) (xy 272.925286 -80.87614)
				)
			)
		)
	)
)
